(kicad_pcb
	(version 20260206)
	(generator "pcbnew")
	(generator_version "10.0")
	(general
		(thickness 1.6)
		(legacy_teardrops no)
	)
	(paper "A4")
	(title_block
		(title "03242023_DA0F0TMBIJ0_F0T_Motherboard_J_brd_V01_OCP.brd")
		(comment 1 "Grand Teton / footprints 1071-1076 of 6105")
	)
	(layers
		(0 "F.Cu" signal "TOP")
		(4 "In1.Cu" signal "GND")
		(6 "In2.Cu" signal "IN1")
		(8 "In3.Cu" signal "GND1")
		(10 "In4.Cu" signal "IN2")
		(12 "In5.Cu" signal "GND2")
		(14 "In6.Cu" signal "IN3")
		(16 "In7.Cu" signal "GND3")
		(18 "In8.Cu" signal "VCC")
		(20 "In9.Cu" signal "VCC1")
		(22 "In10.Cu" signal "GND4")
		(24 "In11.Cu" signal "IN4")
		(26 "In12.Cu" signal "GND5")
		(28 "In13.Cu" signal "IN5")
		(30 "In14.Cu" signal "GND6")
		(32 "In15.Cu" signal "IN6")
		(34 "In16.Cu" signal "GND7")
		(2 "B.Cu" signal "BOTTOM")
		(9 "F.Adhes" user "F.Adhesive")
		(11 "B.Adhes" user "B.Adhesive")
		(13 "F.Paste" user "Package Geometry/Pastemask Top")
		(15 "B.Paste" user "Package Geometry/Pastemask Bottom")
		(5 "F.SilkS" user "Ref Des/Silkscreen Top")
		(7 "B.SilkS" user "Ref Des/Silkscreen Bottom")
		(1 "F.Mask" user "Board Geometry/Soldermask Top")
		(3 "B.Mask" user "Board Geometry/Soldermask Bottom")
		(17 "Dwgs.User" user "User.Drawings")
		(19 "Cmts.User" user "User.Comments")
		(21 "Eco1.User" user "User.Eco1")
		(23 "Eco2.User" user "User.Eco2")
		(25 "Edge.Cuts" user "Board Geometry/Outline")
		(27 "Margin" user)
		(31 "F.CrtYd" user "Package Geometry/Place Bound Top")
		(29 "B.CrtYd" user "Package Geometry/Place Bound Bottom")
		(35 "F.Fab" user "Ref Des/Assembly Top")
		(33 "B.Fab" user "Ref Des/Assembly Bottom")
	)
	(footprint ""
		(layer "F.Cu")
		(at 254.161544 -398.78 90)
		(property "Reference" "PPQ5"
			(at -8.245856 -1.914144 0)
			(unlocked yes)
			(layer "F.SilkS")
			(effects
				(font
					(size 0.7874 0.5842)
					(thickness 0.1524)
				)
				(justify left)
			)
		)
		(property "Value" ""
			(at 0 0 90)
			(layer "F.Fab")
			(effects
				(font
					(size 1.27 1.27)
				)
			)
		)
		(duplicate_pad_numbers_are_jumpers no)
		(fp_line
			(start 2.350008 -2.649982)
			(end 2.350008 -2.4892)
			(stroke
				(width 0.1524)
				(type default)
			)
			(layer "F.SilkS")
		)
		(fp_line
			(start -2.350008 -2.649982)
			(end 2.350008 -2.649982)
			(stroke
				(width 0.1524)
				(type default)
			)
			(layer "F.SilkS")
		)
		(fp_line
			(start -2.350008 -2.4384)
			(end -2.350008 -2.649982)
			(stroke
				(width 0.1524)
				(type default)
			)
			(layer "F.SilkS")
		)
		(fp_line
			(start 2.350008 2.4892)
			(end 2.350008 2.649982)
			(stroke
				(width 0.1524)
				(type default)
			)
			(layer "F.SilkS")
		)
		(fp_line
			(start 2.350008 2.649982)
			(end -2.350008 2.649982)
			(stroke
				(width 0.1524)
				(type default)
			)
			(layer "F.SilkS")
		)
		(fp_line
			(start -2.350008 2.649982)
			(end -2.350008 2.413)
			(stroke
				(width 0.1524)
				(type default)
			)
			(layer "F.SilkS")
		)
		(fp_poly
			(pts
				(xy -3.717544 -1.905) (xy -4.758944 -2.3241) (xy -4.758944 -1.524)
			)
			(stroke
				(width 0)
				(type default)
			)
			(fill yes)
			(layer "F.SilkS")
		)
		(fp_line
			(start 2.350008 -2.649982)
			(end 2.350008 2.649982)
			(stroke
				(width 0.1)
				(type default)
			)
			(layer "F.Fab")
		)
		(fp_line
			(start -2.350008 -2.649982)
			(end 2.350008 -2.649982)
			(stroke
				(width 0.1)
				(type default)
			)
			(layer "F.Fab")
		)
		(fp_line
			(start 2.350008 2.649982)
			(end -2.350008 2.649982)
			(stroke
				(width 0.1)
				(type default)
			)
			(layer "F.Fab")
		)
		(fp_line
			(start -2.350008 2.649982)
			(end -2.350008 -2.649982)
			(stroke
				(width 0.1)
				(type default)
			)
			(layer "F.Fab")
		)
		(fp_poly
			(pts
				(xy -3.717544 -1.905) (xy -4.758944 -2.3241) (xy -4.758944 -1.524)
			)
			(stroke
				(width 0)
				(type default)
			)
			(fill yes)
			(layer "F.Fab")
		)
		(pad "1" smd rect
			(at -2.999994 -1.905)
			(size 0.7112 1.1684)
			(layers "F.Cu" "F.Mask" "F.Paste")
			(net "P12V_AUX")
		)
		(pad "2" smd rect
			(at -2.999994 -0.635)
			(size 0.7112 1.1684)
			(layers "F.Cu" "F.Mask" "F.Paste")
			(net "P12V_AUX")
		)
		(pad "3" smd rect
			(at -2.999994 0.635)
			(size 0.7112 1.1684)
			(layers "F.Cu" "F.Mask" "F.Paste")
			(net "P12V_AUX")
		)
		(pad "4" smd rect
			(at -2.999994 1.905)
			(size 0.7112 1.1684)
			(layers "F.Cu" "F.Mask" "F.Paste")
			(net "P12V_HSC_GATE_G1")
		)
		(pad "5" smd circle
			(at 0.925068 0)
			(size 0 0)
			(layers "F.Cu" "F.Mask" "F.Paste")
			(net "P12V_MAIN_R")
		)
		(zone
			(layer "F.Cu")
			(hatch none 0.5)
			(connect_pads
				(clearance 0)
			)
			(min_thickness 0.25)
			(keepout
				(tracks not_allowed)
				(vias allowed)
				(pads allowed)
				(copperpour not_allowed)
				(footprints allowed)
			)
			(placement
				(enabled no)
				(sheetname "")
			)
			(fill
				(thermal_gap 0.5)
				(thermal_bridge_width 0.5)
				(island_removal_mode 0)
			)
			(polygon
				(pts
					(xy 252.002544 -397.3322) (xy 256.320544 -397.3322) (xy 256.320544 -397.33982) (xy 256.803144 -397.33982)
					(xy 256.803144 -396.4305) (xy 251.519944 -396.4305) (xy 251.519944 -397.3322)
				)
			)
		)
	)
	(footprint ""
		(layer "F.Cu")
		(at 120.315482 -14.20749)
		(property "Reference" "R4185"
			(at 0 0 0)
			(layer "F.SilkS")
			(hide yes)
			(effects
				(font
					(size 1.27 1.27)
				)
			)
		)
		(property "Value" ""
			(at 0 0 0)
			(layer "F.Fab")
			(effects
				(font
					(size 1.27 1.27)
				)
			)
		)
		(duplicate_pad_numbers_are_jumpers no)
		(fp_line
			(start -0.7874 -0.4064)
			(end 0.7874 -0.4064)
			(stroke
				(width 0.1524)
				(type default)
			)
			(layer "F.SilkS")
		)
		(fp_line
			(start -0.7874 0.4064)
			(end -0.7874 -0.4064)
			(stroke
				(width 0.1524)
				(type default)
			)
			(layer "F.SilkS")
		)
		(fp_line
			(start 0.7874 -0.4064)
			(end 0.7874 0.4064)
			(stroke
				(width 0.1524)
				(type default)
			)
			(layer "F.SilkS")
		)
		(fp_line
			(start 0.7874 0.4064)
			(end -0.7874 0.4064)
			(stroke
				(width 0.1524)
				(type default)
			)
			(layer "F.SilkS")
		)
		(fp_line
			(start -0.67945 -0.305054)
			(end -0.12065 -0.305054)
			(stroke
				(width 0.1)
				(type default)
			)
			(layer "F.Fab")
		)
		(fp_line
			(start -0.67945 0.3048)
			(end -0.67945 -0.305054)
			(stroke
				(width 0.1)
				(type default)
			)
			(layer "F.Fab")
		)
		(fp_line
			(start -0.12065 -0.305054)
			(end -0.12065 -0.2794)
			(stroke
				(width 0.1)
				(type default)
			)
			(layer "F.Fab")
		)
		(fp_line
			(start -0.12065 -0.2794)
			(end 0.12065 -0.2794)
			(stroke
				(width 0.1)
				(type default)
			)
			(layer "F.Fab")
		)
		(fp_line
			(start -0.12065 0.2794)
			(end -0.12065 0.3048)
			(stroke
				(width 0.1)
				(type default)
			)
			(layer "F.Fab")
		)
		(fp_line
			(start -0.12065 0.3048)
			(end -0.67945 0.3048)
			(stroke
				(width 0.1)
				(type default)
			)
			(layer "F.Fab")
		)
		(fp_line
			(start 0.120396 0.2794)
			(end -0.12065 0.2794)
			(stroke
				(width 0.1)
				(type default)
			)
			(layer "F.Fab")
		)
		(fp_line
			(start 0.120396 0.3048)
			(end 0.120396 0.2794)
			(stroke
				(width 0.1)
				(type default)
			)
			(layer "F.Fab")
		)
		(fp_line
			(start 0.12065 -0.3048)
			(end 0.67945 -0.3048)
			(stroke
				(width 0.1)
				(type default)
			)
			(layer "F.Fab")
		)
		(fp_line
			(start 0.12065 -0.2794)
			(end 0.12065 -0.3048)
			(stroke
				(width 0.1)
				(type default)
			)
			(layer "F.Fab")
		)
		(fp_line
			(start 0.67945 -0.3048)
			(end 0.67945 0.3048)
			(stroke
				(width 0.1)
				(type default)
			)
			(layer "F.Fab")
		)
		(fp_line
			(start 0.67945 0.3048)
			(end 0.120396 0.3048)
			(stroke
				(width 0.1)
				(type default)
			)
			(layer "F.Fab")
		)
		(pad "1" smd circle
			(at -0.40005 0)
			(size 0 0)
			(layers "F.Cu" "F.Mask" "F.Paste")
			(net "U273_3_ADD2")
		)
		(pad "2" smd circle
			(at 0.40005 0)
			(size 0 0)
			(layers "F.Cu" "F.Mask" "F.Paste")
			(net "GND")
		)
	)
	(footprint ""
		(layer "F.Cu")
		(at 220.100652 -106.384344)
		(property "Reference" "R2238"
			(at 0 0 0)
			(layer "F.SilkS")
			(hide yes)
			(effects
				(font
					(size 1.27 1.27)
				)
			)
		)
		(property "Value" ""
			(at 0 0 0)
			(layer "F.Fab")
			(effects
				(font
					(size 1.27 1.27)
				)
			)
		)
		(duplicate_pad_numbers_are_jumpers no)
		(fp_line
			(start -0.7874 -0.4064)
			(end 0.7874 -0.4064)
			(stroke
				(width 0.1524)
				(type default)
			)
			(layer "F.SilkS")
		)
		(fp_line
			(start -0.7874 0.4064)
			(end -0.7874 -0.4064)
			(stroke
				(width 0.1524)
				(type default)
			)
			(layer "F.SilkS")
		)
		(fp_line
			(start 0.7874 -0.4064)
			(end 0.7874 0.4064)
			(stroke
				(width 0.1524)
				(type default)
			)
			(layer "F.SilkS")
		)
		(fp_line
			(start 0.7874 0.4064)
			(end -0.7874 0.4064)
			(stroke
				(width 0.1524)
				(type default)
			)
			(layer "F.SilkS")
		)
		(fp_line
			(start -0.67945 -0.305054)
			(end -0.12065 -0.305054)
			(stroke
				(width 0.1)
				(type default)
			)
			(layer "F.Fab")
		)
		(fp_line
			(start -0.67945 0.3048)
			(end -0.67945 -0.305054)
			(stroke
				(width 0.1)
				(type default)
			)
			(layer "F.Fab")
		)
		(fp_line
			(start -0.12065 -0.305054)
			(end -0.12065 -0.2794)
			(stroke
				(width 0.1)
				(type default)
			)
			(layer "F.Fab")
		)
		(fp_line
			(start -0.12065 -0.2794)
			(end 0.12065 -0.2794)
			(stroke
				(width 0.1)
				(type default)
			)
			(layer "F.Fab")
		)
		(fp_line
			(start -0.12065 0.2794)
			(end -0.12065 0.3048)
			(stroke
				(width 0.1)
				(type default)
			)
			(layer "F.Fab")
		)
		(fp_line
			(start -0.12065 0.3048)
			(end -0.67945 0.3048)
			(stroke
				(width 0.1)
				(type default)
			)
			(layer "F.Fab")
		)
		(fp_line
			(start 0.120396 0.2794)
			(end -0.12065 0.2794)
			(stroke
				(width 0.1)
				(type default)
			)
			(layer "F.Fab")
		)
		(fp_line
			(start 0.120396 0.3048)
			(end 0.120396 0.2794)
			(stroke
				(width 0.1)
				(type default)
			)
			(layer "F.Fab")
		)
		(fp_line
			(start 0.12065 -0.3048)
			(end 0.67945 -0.3048)
			(stroke
				(width 0.1)
				(type default)
			)
			(layer "F.Fab")
		)
		(fp_line
			(start 0.12065 -0.2794)
			(end 0.12065 -0.3048)
			(stroke
				(width 0.1)
				(type default)
			)
			(layer "F.Fab")
		)
		(fp_line
			(start 0.67945 -0.3048)
			(end 0.67945 0.3048)
			(stroke
				(width 0.1)
				(type default)
			)
			(layer "F.Fab")
		)
		(fp_line
			(start 0.67945 0.3048)
			(end 0.120396 0.3048)
			(stroke
				(width 0.1)
				(type default)
			)
			(layer "F.Fab")
		)
		(pad "1" smd circle
			(at -0.40005 0)
			(size 0 0)
			(layers "F.Cu" "F.Mask" "F.Paste")
			(net "A_HSC_INAP")
		)
		(pad "2" smd circle
			(at 0.40005 0)
			(size 0 0)
			(layers "F.Cu" "F.Mask" "F.Paste")
			(net "GND")
		)
	)
	(footprint ""
		(layer "F.Cu")
		(at 213.1568 -110.617 90)
		(property "Reference" "U340"
			(at 4.54533 -0.5588 0)
			(unlocked yes)
			(layer "F.SilkS")
			(effects
				(font
					(size 0.7874 0.5842)
					(thickness 0.1524)
				)
			)
		)
		(property "Value" ""
			(at 0 0 90)
			(layer "F.Fab")
			(effects
				(font
					(size 1.27 1.27)
				)
			)
		)
		(duplicate_pad_numbers_are_jumpers no)
		(fp_line
			(start 2.032 -1.549908)
			(end 2.032 1.549908)
			(stroke
				(width 0.1524)
				(type default)
			)
			(layer "F.SilkS")
		)
		(fp_line
			(start 0.508 -1.549908)
			(end 2.032 -1.549908)
			(stroke
				(width 0.1524)
				(type default)
			)
			(layer "F.SilkS")
		)
		(fp_line
			(start -0.508 -1.549908)
			(end 0 -0.762)
			(stroke
				(width 0.1524)
				(type default)
			)
			(layer "F.SilkS")
		)
		(fp_line
			(start -2.032 -1.549908)
			(end -0.508 -1.549908)
			(stroke
				(width 0.1524)
				(type default)
			)
			(layer "F.SilkS")
		)
		(fp_line
			(start 0 -0.762)
			(end 0.508 -1.549908)
			(stroke
				(width 0.1524)
				(type default)
			)
			(layer "F.SilkS")
		)
		(fp_line
			(start 2.032 1.549908)
			(end -2.032 1.549908)
			(stroke
				(width 0.1524)
				(type default)
			)
			(layer "F.SilkS")
		)
		(fp_line
			(start -2.032 1.549908)
			(end -2.032 -1.549908)
			(stroke
				(width 0.1524)
				(type default)
			)
			(layer "F.SilkS")
		)
		(fp_poly
			(pts
				(xy -2.37363 -1.825244) (xy -1.764538 -1.622298) (xy -1.967738 -2.231136)
			)
			(stroke
				(width 0)
				(type default)
			)
			(fill yes)
			(layer "F.SilkS")
		)
		(fp_line
			(start 0.849884 -1.549908)
			(end 0.849884 1.549908)
			(stroke
				(width 0.1)
				(type default)
			)
			(layer "F.Fab")
		)
		(fp_line
			(start -0.849884 -1.549908)
			(end 0.849884 -1.549908)
			(stroke
				(width 0.1)
				(type default)
			)
			(layer "F.Fab")
		)
		(fp_line
			(start 0.849884 1.549908)
			(end -0.849884 1.549908)
			(stroke
				(width 0.1)
				(type default)
			)
			(layer "F.Fab")
		)
		(fp_line
			(start -0.849884 1.549908)
			(end -0.849884 -1.549908)
			(stroke
				(width 0.1)
				(type default)
			)
			(layer "F.Fab")
		)
		(fp_poly
			(pts
				(xy -3.2004 -1.45796) (xy -3.2004 -0.44196) (xy -2.1844 -0.94996)
			)
			(stroke
				(width 0)
				(type default)
			)
			(fill yes)
			(layer "F.Fab")
		)
		(pad "1" smd rect
			(at -1.35001 -0.94996)
			(size 0.6096 1.0668)
			(layers "F.Cu" "F.Mask" "F.Paste")
			(net "UV_P2V5_COMP")
		)
		(pad "2" smd rect
			(at -1.35001 0)
			(size 0.6096 1.0668)
			(layers "F.Cu" "F.Mask" "F.Paste")
			(net "GND")
		)
		(pad "3" smd rect
			(at -1.35001 0.94996)
			(size 0.6096 1.0668)
			(layers "F.Cu" "F.Mask" "F.Paste")
			(net "P12V_AUX_UV_TRIGGER")
		)
		(pad "4" smd rect
			(at 1.35001 0.94996)
			(size 0.6096 1.0668)
			(layers "F.Cu" "F.Mask" "F.Paste")
			(net "IRQ_UV_DETECT_R2_N")
		)
		(pad "5" smd rect
			(at 1.35001 -0.94996)
			(size 0.6096 1.0668)
			(layers "F.Cu" "F.Mask" "F.Paste")
			(net "P12V_AUX")
		)
	)
	(footprint ""
		(layer "F.Cu")
		(at 382.168908 -78.424024 90)
		(property "Reference" "PR1330"
			(at 0 0 90)
			(layer "F.SilkS")
			(hide yes)
			(effects
				(font
					(size 1.27 1.27)
				)
			)
		)
		(property "Value" ""
			(at 0 0 90)
			(layer "F.Fab")
			(effects
				(font
					(size 1.27 1.27)
				)
			)
		)
		(duplicate_pad_numbers_are_jumpers no)
		(fp_line
			(start 0.7874 -0.4064)
			(end 0.7874 0.4064)
			(stroke
				(width 0.1524)
				(type default)
			)
			(layer "F.SilkS")
		)
		(fp_line
			(start -0.7874 -0.4064)
			(end 0.7874 -0.4064)
			(stroke
				(width 0.1524)
				(type default)
			)
			(layer "F.SilkS")
		)
		(fp_line
			(start 0.7874 0.4064)
			(end -0.7874 0.4064)
			(stroke
				(width 0.1524)
				(type default)
			)
			(layer "F.SilkS")
		)
		(fp_line
			(start -0.7874 0.4064)
			(end -0.7874 -0.4064)
			(stroke
				(width 0.1524)
				(type default)
			)
			(layer "F.SilkS")
		)
		(fp_line
			(start -0.12065 -0.305054)
			(end -0.12065 -0.2794)
			(stroke
				(width 0.1)
				(type default)
			)
			(layer "F.Fab")
		)
		(fp_line
			(start -0.67945 -0.305054)
			(end -0.12065 -0.305054)
			(stroke
				(width 0.1)
				(type default)
			)
			(layer "F.Fab")
		)
		(fp_line
			(start 0.67945 -0.3048)
			(end 0.67945 0.3048)
			(stroke
				(width 0.1)
				(type default)
			)
			(layer "F.Fab")
		)
		(fp_line
			(start 0.12065 -0.3048)
			(end 0.67945 -0.3048)
			(stroke
				(width 0.1)
				(type default)
			)
			(layer "F.Fab")
		)
		(fp_line
			(start 0.12065 -0.2794)
			(end 0.12065 -0.3048)
			(stroke
				(width 0.1)
				(type default)
			)
			(layer "F.Fab")
		)
		(fp_line
			(start -0.12065 -0.2794)
			(end 0.12065 -0.2794)
			(stroke
				(width 0.1)
				(type default)
			)
			(layer "F.Fab")
		)
		(fp_line
			(start 0.120396 0.2794)
			(end -0.12065 0.2794)
			(stroke
				(width 0.1)
				(type default)
			)
			(layer "F.Fab")
		)
		(fp_line
			(start -0.12065 0.2794)
			(end -0.12065 0.3048)
			(stroke
				(width 0.1)
				(type default)
			)
			(layer "F.Fab")
		)
		(fp_line
			(start 0.67945 0.3048)
			(end 0.120396 0.3048)
			(stroke
				(width 0.1)
				(type default)
			)
			(layer "F.Fab")
		)
		(fp_line
			(start 0.120396 0.3048)
			(end 0.120396 0.2794)
			(stroke
				(width 0.1)
				(type default)
			)
			(layer "F.Fab")
		)
		(fp_line
			(start -0.12065 0.3048)
			(end -0.67945 0.3048)
			(stroke
				(width 0.1)
				(type default)
			)
			(layer "F.Fab")
		)
		(fp_line
			(start -0.67945 0.3048)
			(end -0.67945 -0.305054)
			(stroke
				(width 0.1)
				(type default)
			)
			(layer "F.Fab")
		)
		(pad "1" smd circle
			(at -0.40005 0 90)
			(size 0 0)
			(layers "F.Cu" "F.Mask" "F.Paste")
			(net "P1V8_PCH_AUX_MODE")
		)
		(pad "2" smd circle
			(at 0.40005 0 90)
			(size 0 0)
			(layers "F.Cu" "F.Mask" "F.Paste")
			(net "GND")
		)
	)
	(footprint ""
		(layer "F.Cu")
		(at 37.990272 -353.35718 -90)
		(property "Reference" "PC1245_P1_4"
			(at 0 0 270)
			(layer "F.SilkS")
			(hide yes)
			(effects
				(font
					(size 1.27 1.27)
				)
			)
		)
		(property "Value" ""
			(at 0 0 270)
			(layer "F.Fab")
			(effects
				(font
					(size 1.27 1.27)
				)
			)
		)
		(duplicate_pad_numbers_are_jumpers no)
		(fp_line
			(start -0.7874 0.4064)
			(end -0.7874 -0.4064)
			(stroke
				(width 0.1524)
				(type default)
			)
			(layer "F.SilkS")
		)
		(fp_line
			(start 0.7874 0.4064)
			(end -0.7874 0.4064)
			(stroke
				(width 0.1524)
				(type default)
			)
			(layer "F.SilkS")
		)
		(fp_line
			(start -0.7874 -0.4064)
			(end 0.7874 -0.4064)
			(stroke
				(width 0.1524)
				(type default)
			)
			(layer "F.SilkS")
		)
		(fp_line
			(start 0.7874 -0.4064)
			(end 0.7874 0.4064)
			(stroke
				(width 0.1524)
				(type default)
			)
			(layer "F.SilkS")
		)
		(fp_line
			(start -0.67945 0.3048)
			(end -0.67945 -0.305054)
			(stroke
				(width 0.1)
				(type default)
			)
			(layer "F.Fab")
		)
		(fp_line
			(start -0.12065 0.3048)
			(end -0.67945 0.3048)
			(stroke
				(width 0.1)
				(type default)
			)
			(layer "F.Fab")
		)
		(fp_line
			(start 0.120396 0.3048)
			(end 0.120396 0.2794)
			(stroke
				(width 0.1)
				(type default)
			)
			(layer "F.Fab")
		)
		(fp_line
			(start 0.67945 0.3048)
			(end 0.120396 0.3048)
			(stroke
				(width 0.1)
				(type default)
			)
			(layer "F.Fab")
		)
		(fp_line
			(start -0.12065 0.2794)
			(end -0.12065 0.3048)
			(stroke
				(width 0.1)
				(type default)
			)
			(layer "F.Fab")
		)
		(fp_line
			(start 0.120396 0.2794)
			(end -0.12065 0.2794)
			(stroke
				(width 0.1)
				(type default)
			)
			(layer "F.Fab")
		)
		(fp_line
			(start -0.12065 -0.2794)
			(end 0.12065 -0.2794)
			(stroke
				(width 0.1)
				(type default)
			)
			(layer "F.Fab")
		)
		(fp_line
			(start 0.12065 -0.2794)
			(end 0.12065 -0.3048)
			(stroke
				(width 0.1)
				(type default)
			)
			(layer "F.Fab")
		)
		(fp_line
			(start 0.12065 -0.3048)
			(end 0.67945 -0.3048)
			(stroke
				(width 0.1)
				(type default)
			)
			(layer "F.Fab")
		)
		(fp_line
			(start 0.67945 -0.3048)
			(end 0.67945 0.3048)
			(stroke
				(width 0.1)
				(type default)
			)
			(layer "F.Fab")
		)
		(fp_line
			(start -0.67945 -0.305054)
			(end -0.12065 -0.305054)
			(stroke
				(width 0.1)
				(type default)
			)
			(layer "F.Fab")
		)
		(fp_line
			(start -0.12065 -0.305054)
			(end -0.12065 -0.2794)
			(stroke
				(width 0.1)
				(type default)
			)
			(layer "F.Fab")
		)
		(pad "1" smd circle
			(at -0.40005 0 270)
			(size 0 0)
			(layers "F.Cu" "F.Mask" "F.Paste")
			(net "PVCCFA_EHV_FIVRA_CPU1_PVCC2")
		)
		(pad "2" smd circle
			(at 0.40005 0 270)
			(size 0 0)
			(layers "F.Cu" "F.Mask" "F.Paste")
			(net "GND")
		)
	)
)
